# Barreleye-G2_Tri-mode Expander-DVT-X01-SKU-BOM-X07-20171222_Final.xls.xlsx — POP_GA (bom)
| FOXCONN TECHNOLOGY GROUP |  |  |  |  |  |  |  |  |  |  |  |  |
| BILL OF MATERIAL |  |  |  |  |  |  |  |  |  |  |  |  |
| REV OF  BOM |  | CUSTOMER | <name> |  | CUSTOMER P/N |  | PRODUCT CODE |  | PWA  REV |  | DATE |  |
| Sourcing (Single/Sole/Multi) | Critical Commodity (Y or N) | Component Class (1, 2, other) | Customer PSL (Y or N) | Item Number | Foxconn P/N | Customer P/N | Part Description | Manufacturer  Full Name | Manufacturer  Part Number | Qty | RoHS Status | Location |
